# S9S_MB_2U (Grand Teton) — schematic netlist excerpt (pin names and nets, part order shuffled) for the footprints in the layout excerpt that follows; sources: Cadence DE-HDL packaged netlist, KiCad conversion of 03242023_DA0F0TMBIJ0_F0T_Motherboard_J_brd_V01_OCP.brd

R43  Q_RES  15.4K 1% CHIP  pkg 0402LF  page 99 : A = PD_CHA_CPU1_DIMM2_SAA ; B = GND
PR2517  Q_RES  10 1% EMPTY  pkg 0402LF  page 304 : A = P12V_HSC_ADC_N ; B = P12V_HSC_SENSE2_R3_N
PC455_P1_1  Q_CAP  22UF 4V 20% X6S  pkg C0805  page 293 : A = PVCCINFAON_CPU1 ; B = GND

(kicad_pcb
	(version 20260206)
	(generator "pcbnew")
	(generator_version "10.0")
	(general
		(thickness 1.6)
		(legacy_teardrops no)
	)
	(paper "A4")
	(title_block
		(title "03242023_DA0F0TMBIJ0_F0T_Motherboard_J_brd_V01_OCP.brd")
		(comment 1 "Grand Teton / footprints 4396-4398 of 6105")
	)
	(layers
		(0 "F.Cu" signal "TOP")
		(4 "In1.Cu" signal "GND")
		(6 "In2.Cu" signal "IN1")
		(8 "In3.Cu" signal "GND1")
		(10 "In4.Cu" signal "IN2")
		(12 "In5.Cu" signal "GND2")
		(14 "In6.Cu" signal "IN3")
		(16 "In7.Cu" signal "GND3")
		(18 "In8.Cu" signal "VCC")
		(20 "In9.Cu" signal "VCC1")
		(22 "In10.Cu" signal "GND4")
		(24 "In11.Cu" signal "IN4")
		(26 "In12.Cu" signal "GND5")
		(28 "In13.Cu" signal "IN5")
		(30 "In14.Cu" signal "GND6")
		(32 "In15.Cu" signal "IN6")
		(34 "In16.Cu" signal "GND7")
		(2 "B.Cu" signal "BOTTOM")
		(9 "F.Adhes" user "F.Adhesive")
		(11 "B.Adhes" user "B.Adhesive")
		(13 "F.Paste" user "Package Geometry/Pastemask Top")
		(15 "B.Paste" user "Package Geometry/Pastemask Bottom")
		(5 "F.SilkS" user "Ref Des/Silkscreen Top")
		(7 "B.SilkS" user "Ref Des/Silkscreen Bottom")
		(1 "F.Mask" user "Board Geometry/Soldermask Top")
		(3 "B.Mask" user "Board Geometry/Soldermask Bottom")
		(17 "Dwgs.User" user "User.Drawings")
		(19 "Cmts.User" user "User.Comments")
		(21 "Eco1.User" user "User.Eco1")
		(23 "Eco2.User" user "User.Eco2")
		(25 "Edge.Cuts" user "Board Geometry/Outline")
		(27 "Margin" user)
		(31 "F.CrtYd" user "Package Geometry/Place Bound Top")
		(29 "B.CrtYd" user "Package Geometry/Place Bound Bottom")
		(35 "F.Fab" user "Ref Des/Assembly Top")
		(33 "B.Fab" user "Ref Des/Assembly Bottom")
	)
	(footprint ""
		(layer "B.Cu")
		(at 294.91813 -403.031452 90)
		(property "Reference" "PR2517"
			(at 0 0 90)
			(layer "B.SilkS")
			(hide yes)
			(effects
				(font
					(size 1.27 1.27)
				)
				(justify mirror)
			)
		)
		(property "Value" ""
			(at 0 0 90)
			(layer "B.Fab")
			(effects
				(font
					(size 1.27 1.27)
				)
				(justify mirror)
			)
		)
		(duplicate_pad_numbers_are_jumpers no)
		(fp_line
			(start 0.7874 -0.4064)
			(end -0.7874 -0.4064)
			(stroke
				(width 0.1524)
				(type default)
			)
			(layer "B.SilkS")
		)
		(fp_line
			(start -0.7874 -0.4064)
			(end -0.7874 0.4064)
			(stroke
				(width 0.1524)
				(type default)
			)
			(layer "B.SilkS")
		)
		(fp_line
			(start 0.7874 0.4064)
			(end 0.7874 -0.4064)
			(stroke
				(width 0.1524)
				(type default)
			)
			(layer "B.SilkS")
		)
		(fp_line
			(start -0.7874 0.4064)
			(end 0.7874 0.4064)
			(stroke
				(width 0.1524)
				(type default)
			)
			(layer "B.SilkS")
		)
		(fp_line
			(start 0.67945 -0.305054)
			(end 0.12065 -0.305054)
			(stroke
				(width 0.1)
				(type default)
			)
			(layer "B.Fab")
		)
		(fp_line
			(start 0.12065 -0.305054)
			(end 0.12065 -0.2794)
			(stroke
				(width 0.1)
				(type default)
			)
			(layer "B.Fab")
		)
		(fp_line
			(start -0.12065 -0.3048)
			(end -0.67945 -0.3048)
			(stroke
				(width 0.1)
				(type default)
			)
			(layer "B.Fab")
		)
		(fp_line
			(start -0.67945 -0.3048)
			(end -0.67945 0.3048)
			(stroke
				(width 0.1)
				(type default)
			)
			(layer "B.Fab")
		)
		(fp_line
			(start 0.12065 -0.2794)
			(end -0.12065 -0.2794)
			(stroke
				(width 0.1)
				(type default)
			)
			(layer "B.Fab")
		)
		(fp_line
			(start -0.12065 -0.2794)
			(end -0.12065 -0.3048)
			(stroke
				(width 0.1)
				(type default)
			)
			(layer "B.Fab")
		)
		(fp_line
			(start 0.12065 0.2794)
			(end 0.12065 0.3048)
			(stroke
				(width 0.1)
				(type default)
			)
			(layer "B.Fab")
		)
		(fp_line
			(start -0.120396 0.2794)
			(end 0.12065 0.2794)
			(stroke
				(width 0.1)
				(type default)
			)
			(layer "B.Fab")
		)
		(fp_line
			(start 0.67945 0.3048)
			(end 0.67945 -0.305054)
			(stroke
				(width 0.1)
				(type default)
			)
			(layer "B.Fab")
		)
		(fp_line
			(start 0.12065 0.3048)
			(end 0.67945 0.3048)
			(stroke
				(width 0.1)
				(type default)
			)
			(layer "B.Fab")
		)
		(fp_line
			(start -0.120396 0.3048)
			(end -0.120396 0.2794)
			(stroke
				(width 0.1)
				(type default)
			)
			(layer "B.Fab")
		)
		(fp_line
			(start -0.67945 0.3048)
			(end -0.120396 0.3048)
			(stroke
				(width 0.1)
				(type default)
			)
			(layer "B.Fab")
		)
		(pad "1" smd circle
			(at 0.40005 0 270)
			(size 0 0)
			(layers "B.Cu" "B.Mask" "B.Paste")
			(net "P12V_HSC_ADC_N")
		)
		(pad "2" smd circle
			(at -0.40005 0 270)
			(size 0 0)
			(layers "B.Cu" "B.Mask" "B.Paste")
			(net "P12V_HSC_SENSE2_R3_N")
		)
	)
	(footprint ""
		(layer "B.Cu")
		(at 62.246764 -318.993774 -90)
		(property "Reference" "R43"
			(at 0 0 90)
			(layer "B.SilkS")
			(hide yes)
			(effects
				(font
					(size 1.27 1.27)
				)
				(justify mirror)
			)
		)
		(property "Value" ""
			(at 0 0 90)
			(layer "B.Fab")
			(effects
				(font
					(size 1.27 1.27)
				)
				(justify mirror)
			)
		)
		(duplicate_pad_numbers_are_jumpers no)
		(fp_line
			(start -0.7874 0.4064)
			(end 0.7874 0.4064)
			(stroke
				(width 0.1524)
				(type default)
			)
			(layer "B.SilkS")
		)
		(fp_line
			(start 0.7874 0.4064)
			(end 0.7874 -0.4064)
			(stroke
				(width 0.1524)
				(type default)
			)
			(layer "B.SilkS")
		)
		(fp_line
			(start -0.7874 -0.4064)
			(end -0.7874 0.4064)
			(stroke
				(width 0.1524)
				(type default)
			)
			(layer "B.SilkS")
		)
		(fp_line
			(start 0.7874 -0.4064)
			(end -0.7874 -0.4064)
			(stroke
				(width 0.1524)
				(type default)
			)
			(layer "B.SilkS")
		)
		(fp_line
			(start -0.67945 0.3048)
			(end -0.120396 0.3048)
			(stroke
				(width 0.1)
				(type default)
			)
			(layer "B.Fab")
		)
		(fp_line
			(start -0.120396 0.3048)
			(end -0.120396 0.2794)
			(stroke
				(width 0.1)
				(type default)
			)
			(layer "B.Fab")
		)
		(fp_line
			(start 0.12065 0.3048)
			(end 0.67945 0.3048)
			(stroke
				(width 0.1)
				(type default)
			)
			(layer "B.Fab")
		)
		(fp_line
			(start 0.67945 0.3048)
			(end 0.67945 -0.305054)
			(stroke
				(width 0.1)
				(type default)
			)
			(layer "B.Fab")
		)
		(fp_line
			(start -0.120396 0.2794)
			(end 0.12065 0.2794)
			(stroke
				(width 0.1)
				(type default)
			)
			(layer "B.Fab")
		)
		(fp_line
			(start 0.12065 0.2794)
			(end 0.12065 0.3048)
			(stroke
				(width 0.1)
				(type default)
			)
			(layer "B.Fab")
		)
		(fp_line
			(start -0.12065 -0.2794)
			(end -0.12065 -0.3048)
			(stroke
				(width 0.1)
				(type default)
			)
			(layer "B.Fab")
		)
		(fp_line
			(start 0.12065 -0.2794)
			(end -0.12065 -0.2794)
			(stroke
				(width 0.1)
				(type default)
			)
			(layer "B.Fab")
		)
		(fp_line
			(start -0.67945 -0.3048)
			(end -0.67945 0.3048)
			(stroke
				(width 0.1)
				(type default)
			)
			(layer "B.Fab")
		)
		(fp_line
			(start -0.12065 -0.3048)
			(end -0.67945 -0.3048)
			(stroke
				(width 0.1)
				(type default)
			)
			(layer "B.Fab")
		)
		(fp_line
			(start 0.12065 -0.305054)
			(end 0.12065 -0.2794)
			(stroke
				(width 0.1)
				(type default)
			)
			(layer "B.Fab")
		)
		(fp_line
			(start 0.67945 -0.305054)
			(end 0.12065 -0.305054)
			(stroke
				(width 0.1)
				(type default)
			)
			(layer "B.Fab")
		)
		(pad "1" smd circle
			(at 0.40005 0 90)
			(size 0 0)
			(layers "B.Cu" "B.Mask" "B.Paste")
			(net "PD_CHA_CPU1_DIMM2_SAA")
		)
		(pad "2" smd circle
			(at -0.40005 0 90)
			(size 0 0)
			(layers "B.Cu" "B.Mask" "B.Paste")
			(net "GND")
		)
	)
	(footprint ""
		(layer "B.Cu")
		(at 62.996572 -153.08326)
		(property "Reference" "PC455_P1_1"
			(at 0 0 0)
			(layer "B.SilkS")
			(hide yes)
			(effects
				(font
					(size 1.27 1.27)
				)
				(justify mirror)
			)
		)
		(property "Value" ""
			(at 0 0 0)
			(layer "B.Fab")
			(effects
				(font
					(size 1.27 1.27)
				)
				(justify mirror)
			)
		)
		(duplicate_pad_numbers_are_jumpers no)
		(fp_line
			(start -1.524 -0.762)
			(end -1.524 0.762)
			(stroke
				(width 0.1524)
				(type default)
			)
			(layer "B.SilkS")
		)
		(fp_line
			(start -1.524 0.762)
			(end 1.524 0.762)
			(stroke
				(width 0.1524)
				(type default)
			)
			(layer "B.SilkS")
		)
		(fp_line
			(start 1.524 -0.762)
			(end -1.524 -0.762)
			(stroke
				(width 0.1524)
				(type default)
			)
			(layer "B.SilkS")
		)
		(fp_line
			(start 1.524 0.762)
			(end 1.524 -0.762)
			(stroke
				(width 0.1524)
				(type default)
			)
			(layer "B.SilkS")
		)
		(fp_line
			(start -1.1049 -0.724916)
			(end 1.1049 -0.724916)
			(stroke
				(width 0.1)
				(type default)
			)
			(layer "B.Fab")
		)
		(fp_line
			(start -1.1049 0.724916)
			(end -1.1049 -0.724916)
			(stroke
				(width 0.1)
				(type default)
			)
			(layer "B.Fab")
		)
		(fp_line
			(start 1.1049 -0.724916)
			(end 1.1049 0.724916)
			(stroke
				(width 0.1)
				(type default)
			)
			(layer "B.Fab")
		)
		(fp_line
			(start 1.1049 0.724916)
			(end -1.1049 0.724916)
			(stroke
				(width 0.1)
				(type default)
			)
			(layer "B.Fab")
		)
		(pad "1" smd rect
			(at 0.889 0)
			(size 1.016 1.27)
			(layers "B.Cu" "B.Mask" "B.Paste")
			(net "PVCCINFAON_CPU1")
		)
		(pad "2" smd rect
			(at -0.889 0)
			(size 1.016 1.27)
			(layers "B.Cu" "B.Mask" "B.Paste")
			(net "GND")
		)
	)
)
